(kicad_pcb
	(version 20221018)
	(generator pcbnew)
	(general
    (thickness 1.62)
  )
	(paper "A4")
	(title_block
    (title "ECP5 - Datacenter Secure Control Module (DC-SCM)")
    (date "2024-07-01")
    (rev "1.2.1")
		(comment 9 "footprints 352-359 of 506")
	)
	(layers
    (0 "F.Cu" signal)
    (1 "In1.Cu" power)
    (2 "In2.Cu" signal)
    (3 "In3.Cu" power)
    (4 "In4.Cu" power)
    (5 "In5.Cu" signal)
    (6 "In6.Cu" power)
    (31 "B.Cu" signal)
    (32 "B.Adhes" user "B.Adhesive")
    (33 "F.Adhes" user "F.Adhesive")
    (34 "B.Paste" user)
    (35 "F.Paste" user)
    (36 "B.SilkS" user "B.Silkscreen")
    (37 "F.SilkS" user "F.Silkscreen")
    (38 "B.Mask" user)
    (39 "F.Mask" user)
    (40 "Dwgs.User" user "User.Drawings")
    (41 "Cmts.User" user "User.Comments")
    (42 "Eco1.User" user "User.Eco1")
    (43 "Eco2.User" user "User.Eco2")
    (44 "Edge.Cuts" user)
    (45 "Margin" user)
    (46 "B.CrtYd" user "B.Courtyard")
    (47 "F.CrtYd" user "F.Courtyard")
    (48 "B.Fab" user)
    (49 "F.Fab" user)
  )
	(footprint "antmicro-footprints:C_0402_1005Metric" (layer "B.Cu")
    (at 102.55 127.4 90)
    (descr "Capacitor SMD 0402")
    (tags "capacitor SMD 0402")
    (property "Author" "Antmicro")
    (property "Dielectric" "X5R")
    (property "License" "Apache-2.0")
    (property "MPN" "GRM155R61H104KE14D")
    (property "Manufacturer" "Murata")
    (property "Public" "False")
    (property "Sheetfile" "fpga-power-supply.kicad_sch")
    (property "Sheetname" "FPGA power supply")
    (property "Val" "100n")
    (property "Voltage" "50V")
    (property "ki_description" "SMD Multilayer Ceramic Capacitor, 0.1 µF, 50 V, 0402 [1005 Metric], ± 10%, X5R, GRM Series")
    (property "ki_keywords" "0402, SMT, CAPACITOR, PASSIVE, CERAMIC, MLCC")
    (attr smd)
    (fp_text reference "C140" (at 22.8 0.05 90) (layer "B.SilkS")
        (effects (font (size 0.7 0.7) (thickness 0.127)) (justify mirror))
    )
    (fp_text value "C_100n_0402" (at 0 -1.17 90) (layer "B.Fab")
        (effects (font (size 1 1) (thickness 0.15)) (justify mirror))
    )
    (fp_text user "Author: Antmicro" (at -0.939 -3.399 270) (layer "B.Fab") hide
        (effects (font (size 0.7 0.7) (thickness 0.15)) (justify left bottom mirror))
    )
    (fp_text user "${REFERENCE}" (at 0 0 90) (layer "B.Fab")
        (effects (font (size 0.25 0.25) (thickness 0.04)) (justify mirror))
    )
    (fp_text user "License: Apache-2.0" (at -0.939 -5.799 270) (layer "B.Fab") hide
        (effects (font (size 0.7 0.7) (thickness 0.15)) (justify left bottom mirror))
    )
    (fp_rect (start -0.925 0.47) (end 0.925 -0.47)
      (stroke (width 0.05) (type default)) (fill none) (layer "B.CrtYd"))
    (fp_line (start -0.494 -0.248) (end -0.494 0.25)
      (stroke (width 0.15) (type solid)) (layer "B.Fab"))
    (fp_line (start -0.494 0.25) (end 0.504 0.25)
      (stroke (width 0.15) (type solid)) (layer "B.Fab"))
    (fp_line (start 0.504 -0.248) (end -0.494 -0.248)
      (stroke (width 0.15) (type solid)) (layer "B.Fab"))
    (fp_line (start 0.504 0.25) (end 0.504 -0.248)
      (stroke (width 0.15) (type solid)) (layer "B.Fab"))
    (pad "1" smd roundrect (at -0.48 0 90) (size 0.59 0.64) (layers "B.Cu" "B.Paste" "B.Mask") (roundrect_rratio 0.25)
      (net 1 "GND") (pintype "passive"))
    (pad "2" smd roundrect (at 0.48 0 90) (size 0.59 0.64) (layers "B.Cu" "B.Paste" "B.Mask") (roundrect_rratio 0.25)
      (net 302 "/FPGA power supply/VCCA0") (pintype "passive"))
  )
	(footprint "antmicro-footprints:C_0402_1005Metric" (layer "B.Cu")
    (at 108.55 127.4 90)
    (descr "Capacitor SMD 0402")
    (tags "capacitor SMD 0402")
    (property "Author" "Antmicro")
    (property "Dielectric" "X5R")
    (property "License" "Apache-2.0")
    (property "MPN" "GRM155R61H104KE14D")
    (property "Manufacturer" "Murata")
    (property "Public" "False")
    (property "Sheetfile" "fpga-power-supply.kicad_sch")
    (property "Sheetname" "FPGA power supply")
    (property "Val" "100n")
    (property "Voltage" "50V")
    (property "ki_description" "SMD Multilayer Ceramic Capacitor, 0.1 µF, 50 V, 0402 [1005 Metric], ± 10%, X5R, GRM Series")
    (property "ki_keywords" "0402, SMT, CAPACITOR, PASSIVE, CERAMIC, MLCC")
    (attr smd)
    (fp_text reference "C141" (at 22.8 -0.05 90) (layer "B.SilkS")
        (effects (font (size 0.7 0.7) (thickness 0.127)) (justify mirror))
    )
    (fp_text value "C_100n_0402" (at 0 -1.17 90) (layer "B.Fab")
        (effects (font (size 1 1) (thickness 0.15)) (justify mirror))
    )
    (fp_text user "Author: Antmicro" (at -0.939 -3.399 270) (layer "B.Fab") hide
        (effects (font (size 0.7 0.7) (thickness 0.15)) (justify left bottom mirror))
    )
    (fp_text user "${REFERENCE}" (at 0 0 90) (layer "B.Fab")
        (effects (font (size 0.25 0.25) (thickness 0.04)) (justify mirror))
    )
    (fp_text user "License: Apache-2.0" (at -0.939 -5.799 270) (layer "B.Fab") hide
        (effects (font (size 0.7 0.7) (thickness 0.15)) (justify left bottom mirror))
    )
    (fp_rect (start -0.925 0.47) (end 0.925 -0.47)
      (stroke (width 0.05) (type default)) (fill none) (layer "B.CrtYd"))
    (fp_line (start -0.494 -0.248) (end -0.494 0.25)
      (stroke (width 0.15) (type solid)) (layer "B.Fab"))
    (fp_line (start -0.494 0.25) (end 0.504 0.25)
      (stroke (width 0.15) (type solid)) (layer "B.Fab"))
    (fp_line (start 0.504 -0.248) (end -0.494 -0.248)
      (stroke (width 0.15) (type solid)) (layer "B.Fab"))
    (fp_line (start 0.504 0.25) (end 0.504 -0.248)
      (stroke (width 0.15) (type solid)) (layer "B.Fab"))
    (pad "1" smd roundrect (at -0.48 0 90) (size 0.59 0.64) (layers "B.Cu" "B.Paste" "B.Mask") (roundrect_rratio 0.25)
      (net 1 "GND") (pintype "passive"))
    (pad "2" smd roundrect (at 0.48 0 90) (size 0.59 0.64) (layers "B.Cu" "B.Paste" "B.Mask") (roundrect_rratio 0.25)
      (net 6 "/FPGA power supply/VCCHTX1") (pintype "passive"))
  )
	(footprint "antmicro-footprints:C_0402_1005Metric" (layer "B.Cu")
    (at 107.95 130.2)
    (descr "Capacitor SMD 0402")
    (tags "capacitor SMD 0402")
    (property "Author" "Antmicro")
    (property "Dielectric" "X5R")
    (property "License" "Apache-2.0")
    (property "MPN" "GRM155R61H104KE14D")
    (property "Manufacturer" "Murata")
    (property "Public" "False")
    (property "Sheetfile" "fpga-power-supply.kicad_sch")
    (property "Sheetname" "FPGA power supply")
    (property "Val" "100n")
    (property "Voltage" "50V")
    (property "ki_description" "SMD Multilayer Ceramic Capacitor, 0.1 µF, 50 V, 0402 [1005 Metric], ± 10%, X5R, GRM Series")
    (property "ki_keywords" "0402, SMT, CAPACITOR, PASSIVE, CERAMIC, MLCC")
    (attr smd)
    (fp_text reference "C142" (at 0.66 20.875) (layer "B.SilkS")
        (effects (font (size 0.7 0.7) (thickness 0.127)) (justify mirror))
    )
    (fp_text value "C_100n_0402" (at 0 -1.17) (layer "B.Fab")
        (effects (font (size 1 1) (thickness 0.15)) (justify mirror))
    )
    (fp_text user "${REFERENCE}" (at 0 0) (layer "B.Fab")
        (effects (font (size 0.25 0.25) (thickness 0.04)) (justify mirror))
    )
    (fp_text user "License: Apache-2.0" (at -0.939 -5.799 180) (layer "B.Fab") hide
        (effects (font (size 0.7 0.7) (thickness 0.15)) (justify left bottom mirror))
    )
    (fp_text user "Author: Antmicro" (at -0.939 -3.399 180) (layer "B.Fab") hide
        (effects (font (size 0.7 0.7) (thickness 0.15)) (justify left bottom mirror))
    )
    (fp_rect (start -0.925 0.47) (end 0.925 -0.47)
      (stroke (width 0.05) (type default)) (fill none) (layer "B.CrtYd"))
    (fp_line (start -0.494 -0.248) (end -0.494 0.25)
      (stroke (width 0.15) (type solid)) (layer "B.Fab"))
    (fp_line (start -0.494 0.25) (end 0.504 0.25)
      (stroke (width 0.15) (type solid)) (layer "B.Fab"))
    (fp_line (start 0.504 -0.248) (end -0.494 -0.248)
      (stroke (width 0.15) (type solid)) (layer "B.Fab"))
    (fp_line (start 0.504 0.25) (end 0.504 -0.248)
      (stroke (width 0.15) (type solid)) (layer "B.Fab"))
    (pad "1" smd roundrect (at -0.48 0) (size 0.59 0.64) (layers "B.Cu" "B.Paste" "B.Mask") (roundrect_rratio 0.25)
      (net 1 "GND") (pintype "passive"))
    (pad "2" smd roundrect (at 0.48 0) (size 0.59 0.64) (layers "B.Cu" "B.Paste" "B.Mask") (roundrect_rratio 0.25)
      (net 303 "/FPGA power supply/VCCA1") (pintype "passive"))
  )
	(footprint "antmicro-footprints:C_0402_1005Metric" (layer "B.Cu")
    (at 101.55 127.4 90)
    (descr "Capacitor SMD 0402")
    (tags "capacitor SMD 0402")
    (property "Author" "Antmicro")
    (property "Dielectric" "X7R")
    (property "License" "Apache-2.0")
    (property "MPN" "GRM155R71H103KA88D")
    (property "Manufacturer" "Murata")
    (property "Public" "False")
    (property "Sheetfile" "fpga-power-supply.kicad_sch")
    (property "Sheetname" "FPGA power supply")
    (property "Val" "10n")
    (property "Voltage" "50V")
    (property "ki_description" "SMD Multilayer Ceramic Capacitor, 10000 pF, 50 V, 0402 [1005 Metric], ± 10%, X7R, GRM Series")
    (property "ki_keywords" "0402, SMT, CAPACITOR, PASSIVE")
    (attr smd)
    (fp_text reference "C144" (at -20.475 2.06 90) (layer "B.SilkS")
        (effects (font (size 0.7 0.7) (thickness 0.127)) (justify mirror))
    )
    (fp_text value "C_10n_0402" (at 0 -1.17 90) (layer "B.Fab")
        (effects (font (size 1 1) (thickness 0.15)) (justify mirror))
    )
    (fp_text user "Author: Antmicro" (at -0.939 -3.399 270) (layer "B.Fab") hide
        (effects (font (size 0.7 0.7) (thickness 0.15)) (justify left bottom mirror))
    )
    (fp_text user "License: Apache-2.0" (at -0.939 -5.799 270) (layer "B.Fab") hide
        (effects (font (size 0.7 0.7) (thickness 0.15)) (justify left bottom mirror))
    )
    (fp_text user "${REFERENCE}" (at 0 0 90) (layer "B.Fab")
        (effects (font (size 0.25 0.25) (thickness 0.04)) (justify mirror))
    )
    (fp_rect (start -0.925 0.47) (end 0.925 -0.47)
      (stroke (width 0.05) (type default)) (fill none) (layer "B.CrtYd"))
    (fp_line (start -0.494 -0.248) (end -0.494 0.25)
      (stroke (width 0.15) (type solid)) (layer "B.Fab"))
    (fp_line (start -0.494 0.25) (end 0.504 0.25)
      (stroke (width 0.15) (type solid)) (layer "B.Fab"))
    (fp_line (start 0.504 -0.248) (end -0.494 -0.248)
      (stroke (width 0.15) (type solid)) (layer "B.Fab"))
    (fp_line (start 0.504 0.25) (end 0.504 -0.248)
      (stroke (width 0.15) (type solid)) (layer "B.Fab"))
    (pad "1" smd roundrect (at -0.48 0 90) (size 0.59 0.64) (layers "B.Cu" "B.Paste" "B.Mask") (roundrect_rratio 0.25)
      (net 1 "GND") (pintype "passive"))
    (pad "2" smd roundrect (at 0.48 0 90) (size 0.59 0.64) (layers "B.Cu" "B.Paste" "B.Mask") (roundrect_rratio 0.25)
      (net 5 "/FPGA power supply/VCCHTX0") (pintype "passive"))
  )
	(footprint "antmicro-footprints:C_0402_1005Metric" (layer "B.Cu")
    (at 104.55 127.4 90)
    (descr "Capacitor SMD 0402")
    (tags "capacitor SMD 0402")
    (property "Author" "Antmicro")
    (property "Dielectric" "X7R")
    (property "License" "Apache-2.0")
    (property "MPN" "GRM155R71H103KA88D")
    (property "Manufacturer" "Murata")
    (property "Public" "False")
    (property "Sheetfile" "fpga-power-supply.kicad_sch")
    (property "Sheetname" "FPGA power supply")
    (property "Val" "10n")
    (property "Voltage" "50V")
    (property "ki_description" "SMD Multilayer Ceramic Capacitor, 10000 pF, 50 V, 0402 [1005 Metric], ± 10%, X7R, GRM Series")
    (property "ki_keywords" "0402, SMT, CAPACITOR, PASSIVE")
    (attr smd)
    (fp_text reference "C146" (at 22.8 0 90) (layer "B.SilkS")
        (effects (font (size 0.7 0.7) (thickness 0.127)) (justify mirror))
    )
    (fp_text value "C_10n_0402" (at 0 -1.17 90) (layer "B.Fab")
        (effects (font (size 1 1) (thickness 0.15)) (justify mirror))
    )
    (fp_text user "${REFERENCE}" (at 0 0 90) (layer "B.Fab")
        (effects (font (size 0.25 0.25) (thickness 0.04)) (justify mirror))
    )
    (fp_text user "License: Apache-2.0" (at -0.939 -5.799 270) (layer "B.Fab") hide
        (effects (font (size 0.7 0.7) (thickness 0.15)) (justify left bottom mirror))
    )
    (fp_text user "Author: Antmicro" (at -0.939 -3.399 270) (layer "B.Fab") hide
        (effects (font (size 0.7 0.7) (thickness 0.15)) (justify left bottom mirror))
    )
    (fp_rect (start -0.925 0.47) (end 0.925 -0.47)
      (stroke (width 0.05) (type default)) (fill none) (layer "B.CrtYd"))
    (fp_line (start -0.494 -0.248) (end -0.494 0.25)
      (stroke (width 0.15) (type solid)) (layer "B.Fab"))
    (fp_line (start -0.494 0.25) (end 0.504 0.25)
      (stroke (width 0.15) (type solid)) (layer "B.Fab"))
    (fp_line (start 0.504 -0.248) (end -0.494 -0.248)
      (stroke (width 0.15) (type solid)) (layer "B.Fab"))
    (fp_line (start 0.504 0.25) (end 0.504 -0.248)
      (stroke (width 0.15) (type solid)) (layer "B.Fab"))
    (pad "1" smd roundrect (at -0.48 0 90) (size 0.59 0.64) (layers "B.Cu" "B.Paste" "B.Mask") (roundrect_rratio 0.25)
      (net 1 "GND") (pintype "passive"))
    (pad "2" smd roundrect (at 0.48 0 90) (size 0.59 0.64) (layers "B.Cu" "B.Paste" "B.Mask") (roundrect_rratio 0.25)
      (net 6 "/FPGA power supply/VCCHTX1") (pintype "passive"))
  )
	(footprint "antmicro-footprints:C_0402_1005Metric" (layer "B.Cu")
    (at 100.45 128.8 90)
    (descr "Capacitor SMD 0402")
    (tags "capacitor SMD 0402")
    (property "Author" "Antmicro")
    (property "Dielectric" "C0G")
    (property "License" "Apache-2.0")
    (property "MPN" "GRM1555C1H102JA01D")
    (property "Manufacturer" "Murata")
    (property "Public" "False")
    (property "Sheetfile" "fpga-power-supply.kicad_sch")
    (property "Sheetname" "FPGA power supply")
    (property "Val" "1n")
    (property "Voltage" "50V")
    (property "ki_description" "SMD Multilayer Ceramic Capacitor, 1000 pF, 50 V, 0402 [1005 Metric], ± 5%, C0G / NP0, GRM Series")
    (property "ki_keywords" "0402, SMT, CAPACITOR, PASSIVE, CERAMIC, MLCC")
    (attr smd)
    (fp_text reference "C149" (at -19.095 2.25 90) (layer "B.SilkS")
        (effects (font (size 0.7 0.7) (thickness 0.127)) (justify mirror))
    )
    (fp_text value "C_1n_0402" (at 0 -1.17 90) (layer "B.Fab")
        (effects (font (size 1 1) (thickness 0.15)) (justify mirror))
    )
    (fp_text user "License: Apache-2.0" (at -0.939 -5.799 270) (layer "B.Fab") hide
        (effects (font (size 0.7 0.7) (thickness 0.15)) (justify left bottom mirror))
    )
    (fp_text user "Author: Antmicro" (at -0.939 -3.399 270) (layer "B.Fab") hide
        (effects (font (size 0.7 0.7) (thickness 0.15)) (justify left bottom mirror))
    )
    (fp_text user "${REFERENCE}" (at 0 0 90) (layer "B.Fab")
        (effects (font (size 0.25 0.25) (thickness 0.04)) (justify mirror))
    )
    (fp_rect (start -0.925 0.47) (end 0.925 -0.47)
      (stroke (width 0.05) (type default)) (fill none) (layer "B.CrtYd"))
    (fp_line (start -0.494 -0.248) (end -0.494 0.25)
      (stroke (width 0.15) (type solid)) (layer "B.Fab"))
    (fp_line (start -0.494 0.25) (end 0.504 0.25)
      (stroke (width 0.15) (type solid)) (layer "B.Fab"))
    (fp_line (start 0.504 -0.248) (end -0.494 -0.248)
      (stroke (width 0.15) (type solid)) (layer "B.Fab"))
    (fp_line (start 0.504 0.25) (end 0.504 -0.248)
      (stroke (width 0.15) (type solid)) (layer "B.Fab"))
    (pad "1" smd roundrect (at -0.48 0 90) (size 0.59 0.64) (layers "B.Cu" "B.Paste" "B.Mask") (roundrect_rratio 0.25)
      (net 1 "GND") (pintype "passive"))
    (pad "2" smd roundrect (at 0.48 0 90) (size 0.59 0.64) (layers "B.Cu" "B.Paste" "B.Mask") (roundrect_rratio 0.25)
      (net 5 "/FPGA power supply/VCCHTX0") (pintype "passive"))
  )
	(footprint "antmicro-footprints:C_0402_1005Metric" (layer "B.Cu")
    (at 109.95 128.8 90)
    (descr "Capacitor SMD 0402")
    (tags "capacitor SMD 0402")
    (property "Author" "Antmicro")
    (property "Dielectric" "C0G")
    (property "License" "Apache-2.0")
    (property "MPN" "GRM1555C1H102JA01D")
    (property "Manufacturer" "Murata")
    (property "Public" "False")
    (property "Sheetfile" "fpga-power-supply.kicad_sch")
    (property "Sheetname" "FPGA power supply")
    (property "Val" "1n")
    (property "Voltage" "50V")
    (property "ki_description" "SMD Multilayer Ceramic Capacitor, 1000 pF, 50 V, 0402 [1005 Metric], ± 5%, C0G / NP0, GRM Series")
    (property "ki_keywords" "0402, SMT, CAPACITOR, PASSIVE, CERAMIC, MLCC")
    (attr smd)
    (fp_text reference "C151" (at 23.5 0 90) (layer "B.SilkS")
        (effects (font (size 0.7 0.7) (thickness 0.127)) (justify mirror))
    )
    (fp_text value "C_1n_0402" (at 0 -1.17 90) (layer "B.Fab")
        (effects (font (size 1 1) (thickness 0.15)) (justify mirror))
    )
    (fp_text user "${REFERENCE}" (at 0 0 90) (layer "B.Fab")
        (effects (font (size 0.25 0.25) (thickness 0.04)) (justify mirror))
    )
    (fp_text user "Author: Antmicro" (at -0.939 -3.399 270) (layer "B.Fab") hide
        (effects (font (size 0.7 0.7) (thickness 0.15)) (justify left bottom mirror))
    )
    (fp_text user "License: Apache-2.0" (at -0.939 -5.799 270) (layer "B.Fab") hide
        (effects (font (size 0.7 0.7) (thickness 0.15)) (justify left bottom mirror))
    )
    (fp_rect (start -0.925 0.47) (end 0.925 -0.47)
      (stroke (width 0.05) (type default)) (fill none) (layer "B.CrtYd"))
    (fp_line (start -0.494 -0.248) (end -0.494 0.25)
      (stroke (width 0.15) (type solid)) (layer "B.Fab"))
    (fp_line (start -0.494 0.25) (end 0.504 0.25)
      (stroke (width 0.15) (type solid)) (layer "B.Fab"))
    (fp_line (start 0.504 -0.248) (end -0.494 -0.248)
      (stroke (width 0.15) (type solid)) (layer "B.Fab"))
    (fp_line (start 0.504 0.25) (end 0.504 -0.248)
      (stroke (width 0.15) (type solid)) (layer "B.Fab"))
    (pad "1" smd roundrect (at -0.48 0 90) (size 0.59 0.64) (layers "B.Cu" "B.Paste" "B.Mask") (roundrect_rratio 0.25)
      (net 1 "GND") (pintype "passive"))
    (pad "2" smd roundrect (at 0.48 0 90) (size 0.59 0.64) (layers "B.Cu" "B.Paste" "B.Mask") (roundrect_rratio 0.25)
      (net 6 "/FPGA power supply/VCCHTX1") (pintype "passive"))
  )
	(footprint "antmicro-footprints:C_0402_1005Metric" (layer "B.Cu")
    (at 106.75 117.05 -90)
    (descr "Capacitor SMD 0402")
    (tags "capacitor SMD 0402")
    (property "Author" "Antmicro")
    (property "Dielectric" "")
    (property "License" "Apache-2.0")
    (property "MPN" "C1005X5R1E474M050BB")
    (property "Manufacturer" "TDK")
    (property "Public" "False")
    (property "Sheetfile" "fpga-power-supply.kicad_sch")
    (property "Sheetname" "FPGA power supply")
    (property "Val" "470n")
    (property "Voltage" "")
    (property "ki_description" "SMD Multilayer Ceramic Capacitor, 0.47 µF, 25 V, 0402 [1005 Metric], ± 20%, X5R, C")
    (property "ki_keywords" "0402, SMT, CAPACITOR, PASSIVE, CERAMIC, MLCC")
    (attr smd)
    (fp_text reference "C194" (at 22.7 0 -90) (layer "B.SilkS")
        (effects (font (size 0.7 0.7) (thickness 0.127)) (justify mirror))
    )
    (fp_text value "C_470n_0402" (at 0 -1.17 -90) (layer "B.Fab")
        (effects (font (size 1 1) (thickness 0.15)) (justify mirror))
    )
    (fp_text user "Author: Antmicro" (at -0.939 -3.399 90) (layer "B.Fab") hide
        (effects (font (size 0.7 0.7) (thickness 0.15)) (justify left bottom mirror))
    )
    (fp_text user "License: Apache-2.0" (at -0.939 -5.799 90) (layer "B.Fab") hide
        (effects (font (size 0.7 0.7) (thickness 0.15)) (justify left bottom mirror))
    )
    (fp_text user "${REFERENCE}" (at 0 0 -90) (layer "B.Fab")
        (effects (font (size 0.25 0.25) (thickness 0.04)) (justify mirror))
    )
    (fp_rect (start -0.925 0.47) (end 0.925 -0.47)
      (stroke (width 0.05) (type default)) (fill none) (layer "B.CrtYd"))
    (fp_line (start -0.494 -0.248) (end -0.494 0.25)
      (stroke (width 0.15) (type solid)) (layer "B.Fab"))
    (fp_line (start -0.494 0.25) (end 0.504 0.25)
      (stroke (width 0.15) (type solid)) (layer "B.Fab"))
    (fp_line (start 0.504 -0.248) (end -0.494 -0.248)
      (stroke (width 0.15) (type solid)) (layer "B.Fab"))
    (fp_line (start 0.504 0.25) (end 0.504 -0.248)
      (stroke (width 0.15) (type solid)) (layer "B.Fab"))
    (pad "1" smd roundrect (at -0.48 0 270) (size 0.59 0.64) (layers "B.Cu" "B.Paste" "B.Mask") (roundrect_rratio 0.25)
      (net 211 "VCC1V2") (pintype "passive"))
    (pad "2" smd roundrect (at 0.48 0 270) (size 0.59 0.64) (layers "B.Cu" "B.Paste" "B.Mask") (roundrect_rratio 0.25)
      (net 1 "GND") (pintype "passive"))
  )
)
